# S9S_MB_2U (Grand Teton) — schematic netlist excerpt (pin names and nets, part order shuffled) for the footprints in the layout excerpt that follows; sources: Cadence DE-HDL packaged netlist, KiCad conversion of 03242023_DA0F0TMBIJ0_F0T_Motherboard_J_brd_V01_OCP.brd

J25  SCONN288_ADR50017P130CC  SCONN288_ADR50017-P130CC IO  pkg DDR288S_1-1VXB  page 106
  VIN_BULK0  = P12V_S3_AUX_CPU1_NVDIMM
  RFU0  = TP_CHE_CPU1_DIMM1_FRU_0
  VIN_MGMT  = P3V3_AUX
  HSCL  = I3C_SPD_DDREFGH_CPU1_LVC1_SCL_R
  HSDA  = I3C_SPD_DDREFGH_CPU1_LVC1_SDA
  VSS0  = GND
  DQ0_A  = M_E_CPU1_SA_DQ<0>
  VSS1  = GND
  DQ1_A  = M_E_CPU1_SA_DQ<1>
  VSS2  = GND
  DQS0_A_T  = M_E_CPU1_SA_DQS_DP<0>
  DQS0_A_C  = M_E_CPU1_SA_DQS_DN<0>
  VSS3  = GND
  DQ4_A  = M_E_CPU1_SA_DQ<4>
  VSS4  = GND
  DQ5_A  = M_E_CPU1_SA_DQ<5>
  VSS5  = GND
  DQ8_A  = M_E_CPU1_SA_DQ<8>
  VSS6  = GND
  DQ9_A  = M_E_CPU1_SA_DQ<9>
  VSS7  = GND
  DQS1_A_T  = M_E_CPU1_SA_DQS_DP<1>
  DQS1_A_C  = M_E_CPU1_SA_DQS_DN<1>
  VSS8  = GND
  DQ12_A  = M_E_CPU1_SA_DQ<12>
  VSS9  = GND
  DQ13_A  = M_E_CPU1_SA_DQ<13>
  VSS10  = GND
  DQ16_A  = M_E_CPU1_SA_DQ<16>
  VSS11  = GND
  DQ17_A  = M_E_CPU1_SA_DQ<17>
  VSS12  = GND
  DQS2_A_T  = M_E_CPU1_SA_DQS_DP<2>
  DQS2_A_C  = M_E_CPU1_SA_DQS_DN<2>
  VSS13  = GND
  DQ20_A  = M_E_CPU1_SA_DQ<20>
  VSS14  = GND
  DQ21_A  = M_E_CPU1_SA_DQ<21>
  VSS15  = GND
  DQ24_A  = M_E_CPU1_SA_DQ<24>
  VSS16  = GND
  DQ25_A  = M_E_CPU1_SA_DQ<25>
  VSS17  = GND
  DQS3_A_T  = M_E_CPU1_SA_DQS_DP<3>
  DQS3_A_C  = M_E_CPU1_SA_DQS_DN<3>
  VSS18  = GND
  DQ28_A  = M_E_CPU1_SA_DQ<28>
  VSS19  = GND
  DQ29_A  = M_E_CPU1_SA_DQ<29>
  VSS20  = GND
  CB0_A  = M_E_CPU1_SA_CB<0>
  VSS21  = GND
  CB1_A  = M_E_CPU1_SA_CB<1>
  VSS22  = GND
  DQS4_A_T  = M_E_CPU1_SA_DQS_DP<4>
  DQS4_A_C  = M_E_CPU1_SA_DQS_DN<4>
  VSS23  = GND
  CB4_A  = M_E_CPU1_SA_CB<4>
  VSS24  = GND
  CB5_A  = M_E_CPU1_SA_CB<5>
  VSS25  = GND
  ALERT_N  = M_E_CPU1_ALERT_N
  VSS26  = GND
  CS0_A_N  = M_E_CPU1_SA_CS_N<0>
  VSS27  = GND
  CA0_A  = M_E_CPU1_SA_CA<0>
  VSS28  = GND
  CA2_A  = M_E_CPU1_SA_CA<2>
  VSS29  = GND
  CA4_A  = M_E_CPU1_SA_CA<4>
  VSS30  = GND
  CA6_A  = M_E_CPU1_SA_CA<6>
  VSS31  = GND
  PAR_A  = M_E_CPU1_SA_PAR
  VSS32  = GND
  CA0_B  = M_E_CPU1_SB_CA<0>
  VSS33  = GND
  CA2_B  = M_E_CPU1_SB_CA<2>
  VSS34  = GND
  CA4_B  = M_E_CPU1_SB_CA<4>
  VSS35  = GND
  CA6_B  = M_E_CPU1_SB_CA<6>
  VSS36  = GND
  CS0_B_N  = M_E_CPU1_SB_CS_N<0>
  VSS37  = GND
  \lbd||rsp_a_n\  = M_E_CPU1_SA_RSP<0>
  \lbs||rsp_b_n\  = M_E_CPU1_SB_RSP<0>
  VSS38  = GND
  CB4_B  = M_E_CPU1_SB_CB<4>
  VSS39  = GND
  CB5_B  = M_E_CPU1_SB_CB<5>
  VSS40  = GND
  \dqs9_b_t||tdqs9_b_t||dbi4_b_n\  = M_E_CPU1_SB_DQS_DP<9>
  \dqs9_b_c||tdqs9_b_c\  = M_E_CPU1_SB_DQS_DN<9>
  VSS41  = GND
  CB0_B  = M_E_CPU1_SB_CB<0>
  VSS42  = GND
  CB1_B  = M_E_CPU1_SB_CB<1>
  VSS43  = GND
  DQ0_B  = M_E_CPU1_SB_DQ<0>
  VSS44  = GND
  DQ1_B  = M_E_CPU1_SB_DQ<1>
  VSS45  = GND
  DQS0_B_T  = M_E_CPU1_SB_DQS_DP<0>
  DQS0_B_C  = M_E_CPU1_SB_DQS_DN<0>
  VSS46  = GND
  DQ4_B  = M_E_CPU1_SB_DQ<4>
  VSS47  = GND
  DQ5_B  = M_E_CPU1_SB_DQ<5>
  VSS48  = GND
  DQ8_B  = M_E_CPU1_SB_DQ<8>
  VSS49  = GND
  DQ9_B  = M_E_CPU1_SB_DQ<9>
  VSS50  = GND
  DQS1_B_T  = M_E_CPU1_SB_DQS_DP<1>
  DQS1_B_C  = M_E_CPU1_SB_DQS_DN<1>
  VSS51  = GND
  DQ12_B  = M_E_CPU1_SB_DQ<12>
  VSS52  = GND
  DQ13_B  = M_E_CPU1_SB_DQ<13>
  VSS53  = GND
  DQ16_B  = M_E_CPU1_SB_DQ<16>
  VSS54  = GND
  DQ17_B  = M_E_CPU1_SB_DQ<17>
  VSS55  = GND
  DQS2_B_T  = M_E_CPU1_SB_DQS_DP<2>
  DQS2_B_C  = M_E_CPU1_SB_DQS_DN<2>
  VSS56  = GND
  DQ20_B  = M_E_CPU1_SB_DQ<20>
  VSS57  = GND
  DQ21_B  = M_E_CPU1_SB_DQ<21>
  VSS58  = GND
  DQ24_B  = M_E_CPU1_SB_DQ<24>
  VSS59  = GND
  DQ25_B  = M_E_CPU1_SB_DQ<25>
  VSS60  = GND
  DQS3_B_T  = M_E_CPU1_SB_DQS_DP<3>
  DQS3_B_C  = M_E_CPU1_SB_DQS_DN<3>
  VSS61  = GND
  DQ28_B  = M_E_CPU1_SB_DQ<28>
  VSS62  = GND
  DQ29_B  = M_E_CPU1_SB_DQ<29>
  VSS63  = GND
  RFU1  = TP_CHE_CPU1_DIMM1_FRU_1
  VIN_BULK1  = P12V_S3_AUX_CPU1_NVDIMM
  VIN_BULK2  = P12V_S3_AUX_CPU1_NVDIMM
  \pwr_good||fail_n\  = PWRGD_CHE_CPU1_DIMM1
  HSA  = PD_CHE_CPU1_DIMM1_SAA
  RFU2  = TP_CHE_CPU1_DIMM1_FRU_2
  RFU3  = TP_CHE_CPU1_DIMM1_FRU_3
  VSS64  = GND
  DQ2_A  = M_E_CPU1_SA_DQ<2>
  VSS65  = GND
  DQ3_A  = M_E_CPU1_SA_DQ<3>
  VSS66  = GND
  \dqs5_a_c||tdqs5_a_c||dqs5_a_t||tdqs5_a_t\  = M_E_CPU1_SA_DQS_DN<5>
  \dqs5_a_t||tdqs5_a_t\  = M_E_CPU1_SA_DQS_DP<5>
  VSS67  = GND
  DQ6_A  = M_E_CPU1_SA_DQ<6>
  VSS68  = GND
  DQ7_A  = M_E_CPU1_SA_DQ<7>
  VSS69  = GND
  DQ10_A  = M_E_CPU1_SA_DQ<10>
  VSS70  = GND
  DQ11_A  = M_E_CPU1_SA_DQ<11>
  VSS71  = GND
  \dqs6_a_c||tdqs6_a_c||dqs6_a_t||tdqs6_a_t\  = M_E_CPU1_SA_DQS_DN<6>
  \dqs6_a_t||tdqs6_a_t\  = M_E_CPU1_SA_DQS_DP<6>
  VSS72  = GND
  DQ14_A  = M_E_CPU1_SA_DQ<14>
  VSS73  = GND
  DQ15_A  = M_E_CPU1_SA_DQ<15>
  VSS74  = GND
  DQ18_A  = M_E_CPU1_SA_DQ<18>
  VSS75  = GND
  DQ19_A  = M_E_CPU1_SA_DQ<19>
  VSS76  = GND
  \dqs7_a_c||tdqs7_a_c\  = M_E_CPU1_SA_DQS_DN<7>
  \dqs7_a_t||tdqs7_a_t\  = M_E_CPU1_SA_DQS_DP<7>
  VSS77  = GND
  DQ22_A  = M_E_CPU1_SA_DQ<22>
  VSS78  = GND
  DQ23_A  = M_E_CPU1_SA_DQ<23>
  VSS79  = GND
  DQ26_A  = M_E_CPU1_SA_DQ<26>
  VSS80  = GND
  DQ27_A  = M_E_CPU1_SA_DQ<27>
  VSS81  = GND
  \dqs8_a_c||tdqs8_a_c\  = M_E_CPU1_SA_DQS_DN<8>
  \dqs8_a_t||tdqs8_a_t\  = M_E_CPU1_SA_DQS_DP<8>
  VSS82  = GND
  DQ30_A  = M_E_CPU1_SA_DQ<30>
  VSS83  = GND
  DQ31_A  = M_E_CPU1_SA_DQ<31>
  VSS84  = GND
  CB2_A  = M_E_CPU1_SA_CB<2>
  VSS85  = GND
  CB3_A  = M_E_CPU1_SA_CB<3>
  VSS86  = GND
  \dqs9_a_c||tdqs9_a_c\  = M_E_CPU1_SA_DQS_DN<9>
  \dqs9_a_t||tdqs9_a_t\  = M_E_CPU1_SA_DQS_DP<9>
  VSS87  = GND
  CB6_A  = M_E_CPU1_SA_CB<6>
  VSS88  = GND
  CB7_A  = M_E_CPU1_SA_CB<7>
  VSS89  = GND
  RESET_N  = RST_M_EF_CPU1_FPGA_N
  VSS90  = GND
  CS1_A_N  = M_E_CPU1_SA_CS_N<1>
  VSS91  = GND
  CA1_A  = M_E_CPU1_SA_CA<1>
  VSS92  = GND
  CA3_A  = M_E_CPU1_SA_CA<3>
  VSS93  = GND
  CA5_A  = M_E_CPU1_SA_CA<5>
  VSS94  = GND
  CK_T  = M_E_CPU1_CLK_DP<0>
  CK_C  = M_E_CPU1_CLK_DN<0>
  VSS95  = GND
  RFU4  = TP_CHE_CPU1_DIMM1_FRU_4
  CA1_B  = M_E_CPU1_SB_CA<1>
  VSS96  = GND
  CA3_B  = M_E_CPU1_SB_CA<3>
  VSS97  = GND
  CA5_B  = M_E_CPU1_SB_CA<5>
  VSS98  = GND
  PAR_B  = M_E_CPU1_SB_PAR
  VSS99  = GND
  CS1_B_N  = M_E_CPU1_SB_CS_N<1>
  VSS100  = GND
  RFU5  = TP_CHE_CPU1_DIMM1_FRU_5
  RFU6  = TP_CHE_CPU1_DIMM1_FRU_6
  VSS101  = GND
  CB6_B  = M_E_CPU1_SB_CB<6>
  VSS102  = GND
  CB7_B  = M_E_CPU1_SB_CB<7>
  VSS103  = GND
  DQS4_B_C  = M_E_CPU1_SB_DQS_DN<4>
  DQS4_B_T  = M_E_CPU1_SB_DQS_DP<4>
  VSS104  = GND
  CB2_B  = M_E_CPU1_SB_CB<2>
  VSS105  = GND
  CB3_B  = M_E_CPU1_SB_CB<3>
  VSS106  = GND
  DQ2_B  = M_E_CPU1_SB_DQ<2>
  VSS107  = GND
  DQ3_B  = M_E_CPU1_SB_DQ<3>
  VSS108  = GND
  \dqs5_b_c||tdqs5_b_c\  = M_E_CPU1_SB_DQS_DN<5>
  \dqs5_b_t||tdqs5_b_t\  = M_E_CPU1_SB_DQS_DP<5>
  VSS109  = GND
  DQ6_B  = M_E_CPU1_SB_DQ<6>
  VSS110  = GND
  DQ7_B  = M_E_CPU1_SB_DQ<7>
  VSS111  = GND
  DQ10_B  = M_E_CPU1_SB_DQ<10>
  VSS112  = GND
  DQ11_B  = M_E_CPU1_SB_DQ<11>
  VSS113  = GND
  \dqs6_b_c||tdqs6_b_c\  = M_E_CPU1_SB_DQS_DN<6>
  \dqs6_b_t||tdqs6_b_t\  = M_E_CPU1_SB_DQS_DP<6>
  VSS114  = GND
  DQ14_B  = M_E_CPU1_SB_DQ<14>
  VSS115  = GND
  DQ15_B  = M_E_CPU1_SB_DQ<15>
  VSS116  = GND
  DQ18_B  = M_E_CPU1_SB_DQ<18>
  VSS117  = GND
  DQ19_B  = M_E_CPU1_SB_DQ<19>
  VSS118  = GND
  \dqs7_b_c||tdqs7_b_c\  = M_E_CPU1_SB_DQS_DN<7>
  \dqs7_b_t||tdqs7_b_t\  = M_E_CPU1_SB_DQS_DP<7>
  VSS119  = GND
  DQ22_B  = M_E_CPU1_SB_DQ<22>
  VSS120  = GND
  DQ23_B  = M_E_CPU1_SB_DQ<23>
  VSS121  = GND
  DQ26_B  = M_E_CPU1_SB_DQ<26>
  VSS122  = GND
  DQ27_B  = M_E_CPU1_SB_DQ<27>
  VSS123  = GND
  \dqs8_b_c||tdqs8_b_c\  = M_E_CPU1_SB_DQS_DN<8>
  \dqs8_b_t||tdqs8_b_t\  = M_E_CPU1_SB_DQS_DP<8>
  VSS124  = GND
  DQ30_B  = M_E_CPU1_SB_DQ<30>
  VSS125  = GND
  DQ31_B  = M_E_CPU1_SB_DQ<31>
  VSS126  = GND
  G1  = GND
  G2  = GND
  G3  = GND

(kicad_pcb
	(version 20260206)
	(generator "pcbnew")
	(generator_version "10.0")
	(general
		(thickness 1.6)
		(legacy_teardrops no)
	)
	(paper "A4")
	(title_block
		(title "03242023_DA0F0TMBIJ0_F0T_Motherboard_J_brd_V01_OCP.brd")
		(comment 1 "Grand Teton / footprint 2539 of 6105 (J25), pads 275-291 of 291")
	)
	(layers
		(0 "F.Cu" signal "TOP")
		(4 "In1.Cu" signal "GND")
		(6 "In2.Cu" signal "IN1")
		(8 "In3.Cu" signal "GND1")
		(10 "In4.Cu" signal "IN2")
		(12 "In5.Cu" signal "GND2")
		(14 "In6.Cu" signal "IN3")
		(16 "In7.Cu" signal "GND3")
		(18 "In8.Cu" signal "VCC")
		(20 "In9.Cu" signal "VCC1")
		(22 "In10.Cu" signal "GND4")
		(24 "In11.Cu" signal "IN4")
		(26 "In12.Cu" signal "GND5")
		(28 "In13.Cu" signal "IN5")
		(30 "In14.Cu" signal "GND6")
		(32 "In15.Cu" signal "IN6")
		(34 "In16.Cu" signal "GND7")
		(2 "B.Cu" signal "BOTTOM")
		(9 "F.Adhes" user "F.Adhesive")
		(11 "B.Adhes" user "B.Adhesive")
		(13 "F.Paste" user "Package Geometry/Pastemask Top")
		(15 "B.Paste" user "Package Geometry/Pastemask Bottom")
		(5 "F.SilkS" user "Ref Des/Silkscreen Top")
		(7 "B.SilkS" user "Ref Des/Silkscreen Bottom")
		(1 "F.Mask" user "Board Geometry/Soldermask Top")
		(3 "B.Mask" user "Board Geometry/Soldermask Bottom")
		(17 "Dwgs.User" user "User.Drawings")
		(19 "Cmts.User" user "User.Comments")
		(21 "Eco1.User" user "User.Eco1")
		(23 "Eco2.User" user "User.Eco2")
		(25 "Edge.Cuts" user "Board Geometry/Outline")
		(27 "Margin" user)
		(31 "F.CrtYd" user "Package Geometry/Place Bound Top")
		(29 "B.CrtYd" user "Package Geometry/Place Bound Bottom")
		(35 "F.Fab" user "Ref Des/Assembly Top")
		(33 "B.Fab" user "Ref Des/Assembly Bottom")
	)
	(footprint ""
		(layer "F.Cu")
		(at 168.40708 -258.091686)
		(property "Reference" "J25"
			(at -3.683 -81.702148 0)
			(unlocked yes)
			(layer "F.SilkS")
			(effects
				(font
					(size 0.7874 0.5842)
					(thickness 0.1524)
				)
				(justify left)
			)
		)
		(property "Value" ""
			(at 0 0 0)
			(layer "F.Fab")
			(effects
				(font
					(size 1.27 1.27)
				)
			)
		)
		(duplicate_pad_numbers_are_jumpers no)
		(pad "275" smd rect
			(at 2.050034 52.274978 270)
			(size 0.519938 1.4986)
			(layers "F.Cu" "F.Mask" "F.Paste")
			(net "GND")
		)
		(pad "276" smd rect
			(at 2.050034 53.125116 270)
			(size 0.519938 1.4986)
			(layers "F.Cu" "F.Mask" "F.Paste")
			(net "M_E_CPU1_SB_DQ<23>")
		)
		(pad "277" smd rect
			(at 2.050034 53.975 270)
			(size 0.519938 1.4986)
			(layers "F.Cu" "F.Mask" "F.Paste")
			(net "GND")
		)
		(pad "278" smd rect
			(at 2.050034 54.824884 270)
			(size 0.519938 1.4986)
			(layers "F.Cu" "F.Mask" "F.Paste")
			(net "M_E_CPU1_SB_DQ<26>")
		)
		(pad "279" smd rect
			(at 2.050034 55.675022 270)
			(size 0.519938 1.4986)
			(layers "F.Cu" "F.Mask" "F.Paste")
			(net "GND")
		)
		(pad "280" smd rect
			(at 2.050034 56.524906 270)
			(size 0.519938 1.4986)
			(layers "F.Cu" "F.Mask" "F.Paste")
			(net "M_E_CPU1_SB_DQ<27>")
		)
		(pad "281" smd rect
			(at 2.050034 57.375044 270)
			(size 0.519938 1.4986)
			(layers "F.Cu" "F.Mask" "F.Paste")
			(net "GND")
		)
		(pad "282" smd rect
			(at 2.050034 58.224928 270)
			(size 0.519938 1.4986)
			(layers "F.Cu" "F.Mask" "F.Paste")
			(net "M_E_CPU1_SB_DQS_DN<8>")
		)
		(pad "283" smd rect
			(at 2.050034 59.075066 270)
			(size 0.519938 1.4986)
			(layers "F.Cu" "F.Mask" "F.Paste")
			(net "M_E_CPU1_SB_DQS_DP<8>")
		)
		(pad "284" smd rect
			(at 2.050034 59.92495 270)
			(size 0.519938 1.4986)
			(layers "F.Cu" "F.Mask" "F.Paste")
			(net "GND")
		)
		(pad "285" smd rect
			(at 2.050034 60.775088 270)
			(size 0.519938 1.4986)
			(layers "F.Cu" "F.Mask" "F.Paste")
			(net "M_E_CPU1_SB_DQ<30>")
		)
		(pad "286" smd rect
			(at 2.050034 61.624972 270)
			(size 0.519938 1.4986)
			(layers "F.Cu" "F.Mask" "F.Paste")
			(net "GND")
		)
		(pad "287" smd rect
			(at 2.050034 62.47511 270)
			(size 0.519938 1.4986)
			(layers "F.Cu" "F.Mask" "F.Paste")
			(net "M_E_CPU1_SB_DQ<31>")
		)
		(pad "288" smd rect
			(at 2.050034 63.324994 270)
			(size 0.519938 1.4986)
			(layers "F.Cu" "F.Mask" "F.Paste")
			(net "GND")
		)
		(pad "G1" thru_hole oval
			(at 0 -68.97497)
			(size 2.8194 1.5748)
			(drill oval 2.4384 1.1938)
			(layers "*.Cu" "*.Mask")
			(remove_unused_layers no)
			(net "GND")
			(clearance 0.127)
			(thermal_gap 0.127)
		)
		(pad "G2" thru_hole oval
			(at 0 3.875024)
			(size 2.8194 1.5748)
			(drill oval 2.4384 1.1938)
			(layers "*.Cu" "*.Mask")
			(remove_unused_layers no)
			(net "GND")
			(clearance 0.127)
			(thermal_gap 0.127)
		)
		(pad "G3" thru_hole oval
			(at 0 68.97497)
			(size 2.8194 1.5748)
			(drill oval 2.4384 1.1938)
			(layers "*.Cu" "*.Mask")
			(remove_unused_layers no)
			(net "GND")
			(clearance 0.127)
			(thermal_gap 0.127)
		)
	)
)
